FILE_TYPE = MACRO_DRAWING;
SET COLOR_WIRE YELLOW;
SET COLOR_PROP ORANGE;
SET COLOR_DOT WHITE;
SET COLOR_ARC YELLOW;
SET COLOR_BODY GREEN;
SET COLOR_NOTE PURPLE;
SET PROP_DISPLAY VALUE;
SET PAGE_NUMBER P405;
FORCEADD PT5161LRS..6
(-7750 4425);
FORCEPROP 1 LAST LOCATION U6011
J 0
(-8100 6050);
DISPLAY 0.723404 (-8100 6050);
PAINT GREEN (-8100 6050);
FORCEPROP 0 LAST $SEC 6
J 0
(-8100 6200);
DISPLAY 0.680851 (-8100 6200);
PAINT MONO (-8100 6200);
DISPLAY INVISIBLE (-8100 6200);
FORCEPROP 0 LAST CDS_SEC 6
J 0
(-8100 6200);
DISPLAY 0.680851 (-8100 6200);
DISPLAY INVISIBLE (-8100 6200);
FORCEPROP 0 LASTPIN (-7300 5575) $PN P29
J 0
(-7290 5585);
DISPLAY 0.680851 (-7290 5585);
PAINT MONO (-7290 5585);
FORCEPROP 0 LASTPIN (-7300 5225) $PN AA29
J 0
(-7290 5235);
DISPLAY 0.680851 (-7290 5235);
PAINT MONO (-7290 5235);
FORCEPROP 0 LASTPIN (-7300 4875) $PN AH29
J 0
(-7290 4885);
DISPLAY 0.680851 (-7290 4885);
PAINT MONO (-7290 4885);
FORCEPROP 0 LASTPIN (-7300 4525) $PN AR29
J 0
(-7290 4535);
DISPLAY 0.680851 (-7290 4535);
PAINT MONO (-7290 4535);
FORCEPROP 0 LASTPIN (-7300 4175) $PN BB29
J 0
(-7290 4185);
DISPLAY 0.680851 (-7290 4185);
PAINT MONO (-7290 4185);
FORCEPROP 0 LASTPIN (-7300 3825) $PN BJ29
J 0
(-7290 3835);
DISPLAY 0.680851 (-7290 3835);
PAINT MONO (-7290 3835);
FORCEPROP 0 LASTPIN (-7300 3475) $PN BT29
J 0
(-7290 3485);
DISPLAY 0.680851 (-7290 3485);
PAINT MONO (-7290 3485);
FORCEPROP 0 LASTPIN (-7300 3125) $PN CC29
J 0
(-7290 3135);
DISPLAY 0.680851 (-7290 3135);
PAINT MONO (-7290 3135);
FORCEPROP 0 LASTPIN (-7300 5675) $PN M26
J 0
(-7290 5685);
DISPLAY 0.680851 (-7290 5685);
PAINT MONO (-7290 5685);
FORCEPROP 0 LASTPIN (-7300 5325) $PN W26
J 0
(-7290 5335);
DISPLAY 0.680851 (-7290 5335);
PAINT MONO (-7290 5335);
FORCEPROP 0 LASTPIN (-7300 4975) $PN AF26
J 0
(-7290 4985);
DISPLAY 0.680851 (-7290 4985);
PAINT MONO (-7290 4985);
FORCEPROP 0 LASTPIN (-7300 4625) $PN AN26
J 0
(-7290 4635);
DISPLAY 0.680851 (-7290 4635);
PAINT MONO (-7290 4635);
FORCEPROP 0 LASTPIN (-7300 4275) $PN AY26
J 0
(-7290 4285);
DISPLAY 0.680851 (-7290 4285);
PAINT MONO (-7290 4285);
FORCEPROP 0 LASTPIN (-7300 3925) $PN BG26
J 0
(-7290 3935);
DISPLAY 0.680851 (-7290 3935);
PAINT MONO (-7290 3935);
FORCEPROP 0 LASTPIN (-7300 3575) $PN BP26
J 0
(-7290 3585);
DISPLAY 0.680851 (-7290 3585);
PAINT MONO (-7290 3585);
FORCEPROP 0 LASTPIN (-7300 3225) $PN CA26
J 0
(-7290 3235);
DISPLAY 0.680851 (-7290 3235);
PAINT MONO (-7290 3235);
FORCEPROP 1 LAST MATERIAL IC
J 0
(-8100 5900);
DISPLAY 0.723404 (-8100 5900);
PAINT GREEN (-8100 5900);
FORCEPROP 2 LAST VALUE PT5161LRS
J 0
(-8100 6100);
DISPLAY 0.680851 (-8100 6100);
FORCEPROP 2 LAST PART_TYPE SMLF
J 0
(-8100 6150);
DISPLAY 0.680851 (-8100 6150);
FORCEPROP 1 LAST NEEDS_NO_SIZE TRUE
J 0
(-7750 4425);
DISPLAY 0.723404 (-7750 4425);
PAINT GREEN (-7750 4425);
DISPLAY INVISIBLE (-7750 4425);
FORCEPROP 1 LAST CDS_LMAN_SYM_OUTLINE -350,1450,300,-1400
J 0
(-7750 4425);
DISPLAY 0.468085 (-7750 4425);
PAINT GREEN (-7750 4425);
DISPLAY INVISIBLE (-7750 4425);
FORCEPROP 2 LAST CDS_LIB pure_quanta
J 0
(-7750 4425);
DISPLAY INVISIBLE (-7750 4425);
FORCEPROP 1 LAST PATH I1
J 0
(-7750 4425);
DISPLAY 0.723404 (-7750 4425);
PAINT GREEN (-7750 4425);
DISPLAY INVISIBLE (-7750 4425);
FORCEPROP 1 LAST PART_NUMBER AJ051610U03
J 0
(-8100 5975);
DISPLAY 0.723404 (-8100 5975);
PAINT GREEN (-8100 5975);
DISPLAY INVISIBLE (-8100 5975);
FORCEADD TAP..1
(-6725 4625);
FORCEPROP 3 LASTPIN (-6775 4625) SIG_NAME P5E_CPU0_P1_RX_DP<12>
J 0
(-6765 4635);
DISPLAY 0.659574 (-6765 4635);
PAINT MONO (-6765 4635);
DISPLAY INVISIBLE (-6765 4635);
FORCEPROP 1 LASTPIN (-6775 4625) BN 12
J 0
(-6787 4633);
DISPLAY 0.680851 (-6787 4633);
PAINT GREEN (-6787 4633);
FORCEPROP 2 LAST CDS_LIB standard
J 0
(-6725 4625);
DISPLAY INVISIBLE (-6725 4625);
FORCEPROP 1 LAST BODY_TYPE PLUMBING
J 0
(-6725 4675);
DISPLAY 0.872340 (-6725 4675);
PAINT GREEN (-6725 4675);
DISPLAY INVISIBLE (-6725 4675);
FORCEPROP 1 LAST HDL_TAP TRUE
J 0
(-6400 4500);
DISPLAY 0.872340 (-6400 4500);
DISPLAY INVISIBLE (-6400 4500);
FORCEPROP 1 LAST PATH I10
J 0
(-6727 4625);
DISPLAY 0.872340 (-6727 4625);
PAINT GREEN (-6727 4625);
DISPLAY INVISIBLE (-6727 4625);
FORCEADD TAP..1
(-6525 4525);
FORCEPROP 3 LASTPIN (-6575 4525) SIG_NAME P5E_CPU0_P1_RX_DN<12>
J 0
(-6565 4535);
DISPLAY 0.659574 (-6565 4535);
PAINT MONO (-6565 4535);
DISPLAY INVISIBLE (-6565 4535);
FORCEPROP 1 LASTPIN (-6575 4525) BN 12
J 0
(-6587 4533);
DISPLAY 0.680851 (-6587 4533);
PAINT GREEN (-6587 4533);
FORCEPROP 2 LAST CDS_LIB standard
J 0
(-6525 4525);
DISPLAY INVISIBLE (-6525 4525);
FORCEPROP 1 LAST BODY_TYPE PLUMBING
J 0
(-6525 4575);
DISPLAY 0.872340 (-6525 4575);
PAINT GREEN (-6525 4575);
DISPLAY INVISIBLE (-6525 4575);
FORCEPROP 1 LAST HDL_TAP TRUE
J 0
(-6200 4400);
DISPLAY 0.872340 (-6200 4400);
DISPLAY INVISIBLE (-6200 4400);
FORCEPROP 1 LAST PATH I11
J 0
(-6527 4525);
DISPLAY 0.872340 (-6527 4525);
PAINT GREEN (-6527 4525);
DISPLAY INVISIBLE (-6527 4525);
FORCEADD TAP..1
(-6725 4975);
FORCEPROP 3 LASTPIN (-6775 4975) SIG_NAME P5E_CPU0_P1_RX_DP<13>
J 0
(-6765 4985);
DISPLAY 0.659574 (-6765 4985);
PAINT MONO (-6765 4985);
DISPLAY INVISIBLE (-6765 4985);
FORCEPROP 1 LASTPIN (-6775 4975) BN 13
J 0
(-6787 4983);
DISPLAY 0.680851 (-6787 4983);
PAINT GREEN (-6787 4983);
FORCEPROP 2 LAST CDS_LIB standard
J 0
(-6725 4975);
DISPLAY INVISIBLE (-6725 4975);
FORCEPROP 1 LAST BODY_TYPE PLUMBING
J 0
(-6725 5025);
DISPLAY 0.872340 (-6725 5025);
PAINT GREEN (-6725 5025);
DISPLAY INVISIBLE (-6725 5025);
FORCEPROP 1 LAST HDL_TAP TRUE
J 0
(-6400 4850);
DISPLAY 0.872340 (-6400 4850);
DISPLAY INVISIBLE (-6400 4850);
FORCEPROP 1 LAST PATH I12
J 0
(-6727 4975);
DISPLAY 0.872340 (-6727 4975);
PAINT GREEN (-6727 4975);
DISPLAY INVISIBLE (-6727 4975);
FORCEADD TAP..1
(-6725 5325);
FORCEPROP 3 LASTPIN (-6775 5325) SIG_NAME P5E_CPU0_P1_RX_DP<14>
J 0
(-6765 5335);
DISPLAY 0.659574 (-6765 5335);
PAINT MONO (-6765 5335);
DISPLAY INVISIBLE (-6765 5335);
FORCEPROP 1 LASTPIN (-6775 5325) BN 14
J 0
(-6787 5333);
DISPLAY 0.680851 (-6787 5333);
PAINT GREEN (-6787 5333);
FORCEPROP 2 LAST CDS_LIB standard
J 0
(-6725 5325);
DISPLAY INVISIBLE (-6725 5325);
FORCEPROP 1 LAST BODY_TYPE PLUMBING
J 0
(-6725 5375);
DISPLAY 0.872340 (-6725 5375);
PAINT GREEN (-6725 5375);
DISPLAY INVISIBLE (-6725 5375);
FORCEPROP 1 LAST HDL_TAP TRUE
J 0
(-6400 5200);
DISPLAY 0.872340 (-6400 5200);
DISPLAY INVISIBLE (-6400 5200);
FORCEPROP 1 LAST PATH I13
J 0
(-6727 5325);
DISPLAY 0.872340 (-6727 5325);
PAINT GREEN (-6727 5325);
DISPLAY INVISIBLE (-6727 5325);
FORCEADD TAP..1
(-6525 4875);
FORCEPROP 3 LASTPIN (-6575 4875) SIG_NAME P5E_CPU0_P1_RX_DN<13>
J 0
(-6565 4885);
DISPLAY 0.659574 (-6565 4885);
PAINT MONO (-6565 4885);
DISPLAY INVISIBLE (-6565 4885);
FORCEPROP 1 LASTPIN (-6575 4875) BN 13
J 0
(-6587 4883);
DISPLAY 0.680851 (-6587 4883);
PAINT GREEN (-6587 4883);
FORCEPROP 2 LAST CDS_LIB standard
J 0
(-6525 4875);
DISPLAY INVISIBLE (-6525 4875);
FORCEPROP 1 LAST BODY_TYPE PLUMBING
J 0
(-6525 4925);
DISPLAY 0.872340 (-6525 4925);
PAINT GREEN (-6525 4925);
DISPLAY INVISIBLE (-6525 4925);
FORCEPROP 1 LAST HDL_TAP TRUE
J 0
(-6200 4750);
DISPLAY 0.872340 (-6200 4750);
DISPLAY INVISIBLE (-6200 4750);
FORCEPROP 1 LAST PATH I14
J 0
(-6527 4875);
DISPLAY 0.872340 (-6527 4875);
PAINT GREEN (-6527 4875);
DISPLAY INVISIBLE (-6527 4875);
FORCEADD TAP..1
(-6525 5225);
FORCEPROP 3 LASTPIN (-6575 5225) SIG_NAME P5E_CPU0_P1_RX_DN<14>
J 0
(-6565 5235);
DISPLAY 0.659574 (-6565 5235);
PAINT MONO (-6565 5235);
DISPLAY INVISIBLE (-6565 5235);
FORCEPROP 1 LASTPIN (-6575 5225) BN 14
J 0
(-6587 5233);
DISPLAY 0.680851 (-6587 5233);
PAINT GREEN (-6587 5233);
FORCEPROP 2 LAST CDS_LIB standard
J 0
(-6525 5225);
DISPLAY INVISIBLE (-6525 5225);
FORCEPROP 1 LAST BODY_TYPE PLUMBING
J 0
(-6525 5275);
DISPLAY 0.872340 (-6525 5275);
PAINT GREEN (-6525 5275);
DISPLAY INVISIBLE (-6525 5275);
FORCEPROP 1 LAST HDL_TAP TRUE
J 0
(-6200 5100);
DISPLAY 0.872340 (-6200 5100);
DISPLAY INVISIBLE (-6200 5100);
FORCEPROP 1 LAST PATH I15
J 0
(-6527 5225);
DISPLAY 0.872340 (-6527 5225);
PAINT GREEN (-6527 5225);
DISPLAY INVISIBLE (-6527 5225);
FORCEADD TAP..1
(-6725 5675);
FORCEPROP 3 LASTPIN (-6775 5675) SIG_NAME P5E_CPU0_P1_RX_DP<15>
J 0
(-6765 5685);
DISPLAY 0.659574 (-6765 5685);
PAINT MONO (-6765 5685);
DISPLAY INVISIBLE (-6765 5685);
FORCEPROP 1 LASTPIN (-6775 5675) BN 15
J 0
(-6787 5683);
DISPLAY 0.680851 (-6787 5683);
PAINT GREEN (-6787 5683);
FORCEPROP 2 LAST CDS_LIB standard
J 0
(-6725 5675);
DISPLAY INVISIBLE (-6725 5675);
FORCEPROP 1 LAST BODY_TYPE PLUMBING
J 0
(-6725 5725);
DISPLAY 0.872340 (-6725 5725);
PAINT GREEN (-6725 5725);
DISPLAY INVISIBLE (-6725 5725);
FORCEPROP 1 LAST HDL_TAP TRUE
J 0
(-6400 5550);
DISPLAY 0.872340 (-6400 5550);
DISPLAY INVISIBLE (-6400 5550);
FORCEPROP 1 LAST PATH I16
J 0
(-6727 5675);
DISPLAY 0.872340 (-6727 5675);
PAINT GREEN (-6727 5675);
DISPLAY INVISIBLE (-6727 5675);
FORCEADD TAP..1
(-6525 5575);
FORCEPROP 3 LASTPIN (-6575 5575) SIG_NAME P5E_CPU0_P1_RX_DN<15>
J 0
(-6565 5585);
DISPLAY 0.659574 (-6565 5585);
PAINT MONO (-6565 5585);
DISPLAY INVISIBLE (-6565 5585);
FORCEPROP 1 LASTPIN (-6575 5575) BN 15
J 0
(-6587 5583);
DISPLAY 0.680851 (-6587 5583);
PAINT GREEN (-6587 5583);
FORCEPROP 2 LAST CDS_LIB standard
J 0
(-6525 5575);
DISPLAY INVISIBLE (-6525 5575);
FORCEPROP 1 LAST BODY_TYPE PLUMBING
J 0
(-6525 5625);
DISPLAY 0.872340 (-6525 5625);
PAINT GREEN (-6525 5625);
DISPLAY INVISIBLE (-6525 5625);
FORCEPROP 1 LAST HDL_TAP TRUE
J 0
(-6200 5450);
DISPLAY 0.872340 (-6200 5450);
DISPLAY INVISIBLE (-6200 5450);
FORCEPROP 1 LAST PATH I17
J 0
(-6527 5575);
DISPLAY 0.872340 (-6527 5575);
PAINT GREEN (-6527 5575);
DISPLAY INVISIBLE (-6527 5575);
FORCEADD OFFPAGE..5
R 2
(-5525 5650);
FORCEPROP 2 LAST $XR0 24 
J 0
(-5336 5650);
DISPLAY 0.638298 (-5336 5650);
PAINT MONO (-5336 5650);
FORCEPROP 2 LAST CDS_LIB standard
J 0
(-5525 5650);
DISPLAY INVISIBLE (-5525 5650);
FORCEPROP 1 LAST OFFPAGE TRUE
J 2
(-5850 5525);
DISPLAY 0.872340 (-5850 5525);
PAINT GREEN (-5850 5525);
DISPLAY INVISIBLE (-5850 5525);
FORCEPROP 1 LAST COMMENT_BODY TRUE
J 2
(-5625 5575);
DISPLAY 0.872340 (-5625 5575);
PAINT GREEN (-5625 5575);
DISPLAY INVISIBLE (-5625 5575);
FORCEPROP 2 LAST PATH I18
J 0
(-5350 5725);
DISPLAY 0.680851 (-5350 5725);
DISPLAY INVISIBLE (-5350 5725);
FORCEADD OFFPAGE..5
R 2
(-5500 5775);
FORCEPROP 2 LAST $XR0 24 
J 0
(-5311 5775);
DISPLAY 0.638298 (-5311 5775);
PAINT MONO (-5311 5775);
FORCEPROP 2 LAST CDS_LIB standard
J 0
(-5500 5775);
DISPLAY INVISIBLE (-5500 5775);
FORCEPROP 1 LAST OFFPAGE TRUE
J 2
(-5825 5650);
DISPLAY 0.872340 (-5825 5650);
PAINT GREEN (-5825 5650);
DISPLAY INVISIBLE (-5825 5650);
FORCEPROP 1 LAST COMMENT_BODY TRUE
J 2
(-5600 5700);
DISPLAY 0.872340 (-5600 5700);
PAINT GREEN (-5600 5700);
DISPLAY INVISIBLE (-5600 5700);
FORCEPROP 2 LAST PATH I19
J 0
(-5325 5850);
DISPLAY 0.680851 (-5325 5850);
DISPLAY INVISIBLE (-5325 5850);
FORCEADD TAP..1
(-6725 3225);
FORCEPROP 3 LASTPIN (-6775 3225) SIG_NAME P5E_CPU0_P1_RX_DP<8>
J 0
(-6765 3235);
DISPLAY 0.659574 (-6765 3235);
PAINT MONO (-6765 3235);
DISPLAY INVISIBLE (-6765 3235);
FORCEPROP 1 LASTPIN (-6775 3225) BN 8
J 0
(-6787 3233);
DISPLAY 0.680851 (-6787 3233);
PAINT GREEN (-6787 3233);
FORCEPROP 2 LAST CDS_LIB standard
J 0
(-6725 3225);
DISPLAY INVISIBLE (-6725 3225);
FORCEPROP 1 LAST BODY_TYPE PLUMBING
J 0
(-6725 3275);
DISPLAY 0.872340 (-6725 3275);
PAINT GREEN (-6725 3275);
DISPLAY INVISIBLE (-6725 3275);
FORCEPROP 1 LAST HDL_TAP TRUE
J 0
(-6400 3100);
DISPLAY 0.872340 (-6400 3100);
DISPLAY INVISIBLE (-6400 3100);
FORCEPROP 1 LAST PATH I2
J 0
(-6727 3225);
DISPLAY 0.872340 (-6727 3225);
PAINT GREEN (-6727 3225);
DISPLAY INVISIBLE (-6727 3225);
FORCEADD TAP..1
(-2175 3225);
FORCEPROP 3 LASTPIN (-2225 3225) SIG_NAME P5E_CPU0_P1_RX_DP<0>
J 0
(-2215 3235);
DISPLAY 0.659574 (-2215 3235);
PAINT MONO (-2215 3235);
DISPLAY INVISIBLE (-2215 3235);
FORCEPROP 1 LASTPIN (-2225 3225) BN 0
J 0
(-2237 3233);
DISPLAY 0.680851 (-2237 3233);
PAINT GREEN (-2237 3233);
FORCEPROP 2 LAST CDS_LIB standard
J 0
(-2175 3225);
DISPLAY INVISIBLE (-2175 3225);
FORCEPROP 1 LAST BODY_TYPE PLUMBING
J 0
(-2175 3275);
DISPLAY 0.872340 (-2175 3275);
PAINT GREEN (-2175 3275);
DISPLAY INVISIBLE (-2175 3275);
FORCEPROP 1 LAST HDL_TAP TRUE
J 0
(-1850 3100);
DISPLAY 0.872340 (-1850 3100);
DISPLAY INVISIBLE (-1850 3100);
FORCEPROP 1 LAST PATH I20
J 0
(-2177 3225);
DISPLAY 0.872340 (-2177 3225);
PAINT GREEN (-2177 3225);
DISPLAY INVISIBLE (-2177 3225);
FORCEADD TAP..1
(-1975 3125);
FORCEPROP 3 LASTPIN (-2025 3125) SIG_NAME P5E_CPU0_P1_RX_DN<0>
J 0
(-2015 3135);
DISPLAY 0.659574 (-2015 3135);
PAINT MONO (-2015 3135);
DISPLAY INVISIBLE (-2015 3135);
FORCEPROP 1 LASTPIN (-2025 3125) BN 0
J 0
(-2037 3133);
DISPLAY 0.680851 (-2037 3133);
PAINT GREEN (-2037 3133);
FORCEPROP 2 LAST CDS_LIB standard
J 0
(-1975 3125);
DISPLAY INVISIBLE (-1975 3125);
FORCEPROP 1 LAST BODY_TYPE PLUMBING
J 0
(-1975 3175);
DISPLAY 0.872340 (-1975 3175);
PAINT GREEN (-1975 3175);
DISPLAY INVISIBLE (-1975 3175);
FORCEPROP 1 LAST HDL_TAP TRUE
J 0
(-1650 3000);
DISPLAY 0.872340 (-1650 3000);
DISPLAY INVISIBLE (-1650 3000);
FORCEPROP 1 LAST PATH I21
J 0
(-1977 3125);
DISPLAY 0.872340 (-1977 3125);
PAINT GREEN (-1977 3125);
DISPLAY INVISIBLE (-1977 3125);
FORCEADD TAP..1
(-1975 3475);
FORCEPROP 3 LASTPIN (-2025 3475) SIG_NAME P5E_CPU0_P1_RX_DN<1>
J 0
(-2015 3485);
DISPLAY 0.659574 (-2015 3485);
PAINT MONO (-2015 3485);
DISPLAY INVISIBLE (-2015 3485);
FORCEPROP 1 LASTPIN (-2025 3475) BN 1
J 0
(-2037 3483);
DISPLAY 0.680851 (-2037 3483);
PAINT GREEN (-2037 3483);
FORCEPROP 2 LAST CDS_LIB standard
J 0
(-1975 3475);
DISPLAY INVISIBLE (-1975 3475);
FORCEPROP 1 LAST BODY_TYPE PLUMBING
J 0
(-1975 3525);
DISPLAY 0.872340 (-1975 3525);
PAINT GREEN (-1975 3525);
DISPLAY INVISIBLE (-1975 3525);
FORCEPROP 1 LAST HDL_TAP TRUE
J 0
(-1650 3350);
DISPLAY 0.872340 (-1650 3350);
DISPLAY INVISIBLE (-1650 3350);
FORCEPROP 1 LAST PATH I22
J 0
(-1977 3475);
DISPLAY 0.872340 (-1977 3475);
PAINT GREEN (-1977 3475);
DISPLAY INVISIBLE (-1977 3475);
FORCEADD TAP..1
(-2175 3575);
FORCEPROP 3 LASTPIN (-2225 3575) SIG_NAME P5E_CPU0_P1_RX_DP<1>
J 0
(-2215 3585);
DISPLAY 0.659574 (-2215 3585);
PAINT MONO (-2215 3585);
DISPLAY INVISIBLE (-2215 3585);
FORCEPROP 1 LASTPIN (-2225 3575) BN 1
J 0
(-2237 3583);
DISPLAY 0.680851 (-2237 3583);
PAINT GREEN (-2237 3583);
FORCEPROP 2 LAST CDS_LIB standard
J 0
(-2175 3575);
DISPLAY INVISIBLE (-2175 3575);
FORCEPROP 1 LAST BODY_TYPE PLUMBING
J 0
(-2175 3625);
DISPLAY 0.872340 (-2175 3625);
PAINT GREEN (-2175 3625);
DISPLAY INVISIBLE (-2175 3625);
FORCEPROP 1 LAST HDL_TAP TRUE
J 0
(-1850 3450);
DISPLAY 0.872340 (-1850 3450);
DISPLAY INVISIBLE (-1850 3450);
FORCEPROP 1 LAST PATH I23
J 0
(-2177 3575);
DISPLAY 0.872340 (-2177 3575);
PAINT GREEN (-2177 3575);
DISPLAY INVISIBLE (-2177 3575);
FORCEADD TAP..1
(-2175 3925);
FORCEPROP 3 LASTPIN (-2225 3925) SIG_NAME P5E_CPU0_P1_RX_DP<2>
J 0
(-2215 3935);
DISPLAY 0.659574 (-2215 3935);
PAINT MONO (-2215 3935);
DISPLAY INVISIBLE (-2215 3935);
FORCEPROP 1 LASTPIN (-2225 3925) BN 2
J 0
(-2237 3933);
DISPLAY 0.680851 (-2237 3933);
PAINT GREEN (-2237 3933);
FORCEPROP 2 LAST CDS_LIB standard
J 0
(-2175 3925);
DISPLAY INVISIBLE (-2175 3925);
FORCEPROP 1 LAST BODY_TYPE PLUMBING
J 0
(-2175 3975);
DISPLAY 0.872340 (-2175 3975);
PAINT GREEN (-2175 3975);
DISPLAY INVISIBLE (-2175 3975);
FORCEPROP 1 LAST HDL_TAP TRUE
J 0
(-1850 3800);
DISPLAY 0.872340 (-1850 3800);
DISPLAY INVISIBLE (-1850 3800);
FORCEPROP 1 LAST PATH I24
J 0
(-2177 3925);
DISPLAY 0.872340 (-2177 3925);
PAINT GREEN (-2177 3925);
DISPLAY INVISIBLE (-2177 3925);
FORCEADD TAP..1
(-1975 3825);
FORCEPROP 3 LASTPIN (-2025 3825) SIG_NAME P5E_CPU0_P1_RX_DN<2>
J 0
(-2015 3835);
DISPLAY 0.659574 (-2015 3835);
PAINT MONO (-2015 3835);
DISPLAY INVISIBLE (-2015 3835);
FORCEPROP 1 LASTPIN (-2025 3825) BN 2
J 0
(-2037 3833);
DISPLAY 0.680851 (-2037 3833);
PAINT GREEN (-2037 3833);
FORCEPROP 2 LAST CDS_LIB standard
J 0
(-1975 3825);
DISPLAY INVISIBLE (-1975 3825);
FORCEPROP 1 LAST BODY_TYPE PLUMBING
J 0
(-1975 3875);
DISPLAY 0.872340 (-1975 3875);
PAINT GREEN (-1975 3875);
DISPLAY INVISIBLE (-1975 3875);
FORCEPROP 1 LAST HDL_TAP TRUE
J 0
(-1650 3700);
DISPLAY 0.872340 (-1650 3700);
DISPLAY INVISIBLE (-1650 3700);
FORCEPROP 1 LAST PATH I25
J 0
(-1977 3825);
DISPLAY 0.872340 (-1977 3825);
PAINT GREEN (-1977 3825);
DISPLAY INVISIBLE (-1977 3825);
FORCEADD TAP..1
(-1975 4175);
FORCEPROP 3 LASTPIN (-2025 4175) SIG_NAME P5E_CPU0_P1_RX_DN<3>
J 0
(-2015 4185);
DISPLAY 0.659574 (-2015 4185);
PAINT MONO (-2015 4185);
DISPLAY INVISIBLE (-2015 4185);
FORCEPROP 1 LASTPIN (-2025 4175) BN 3
J 0
(-2037 4183);
DISPLAY 0.680851 (-2037 4183);
PAINT GREEN (-2037 4183);
FORCEPROP 2 LAST CDS_LIB standard
J 0
(-1975 4175);
DISPLAY INVISIBLE (-1975 4175);
FORCEPROP 1 LAST BODY_TYPE PLUMBING
J 0
(-1975 4225);
DISPLAY 0.872340 (-1975 4225);
PAINT GREEN (-1975 4225);
DISPLAY INVISIBLE (-1975 4225);
FORCEPROP 1 LAST HDL_TAP TRUE
J 0
(-1650 4050);
DISPLAY 0.872340 (-1650 4050);
DISPLAY INVISIBLE (-1650 4050);
FORCEPROP 1 LAST PATH I26
J 0
(-1977 4175);
DISPLAY 0.872340 (-1977 4175);
PAINT GREEN (-1977 4175);
DISPLAY INVISIBLE (-1977 4175);
FORCEADD TAP..1
(-1975 4525);
FORCEPROP 3 LASTPIN (-2025 4525) SIG_NAME P5E_CPU0_P1_RX_DN<4>
J 0
(-2015 4535);
DISPLAY 0.659574 (-2015 4535);
PAINT MONO (-2015 4535);
DISPLAY INVISIBLE (-2015 4535);
FORCEPROP 1 LASTPIN (-2025 4525) BN 4
J 0
(-2037 4533);
DISPLAY 0.680851 (-2037 4533);
PAINT GREEN (-2037 4533);
FORCEPROP 2 LAST CDS_LIB standard
J 0
(-1975 4525);
DISPLAY INVISIBLE (-1975 4525);
FORCEPROP 1 LAST BODY_TYPE PLUMBING
J 0
(-1975 4575);
DISPLAY 0.872340 (-1975 4575);
PAINT GREEN (-1975 4575);
DISPLAY INVISIBLE (-1975 4575);
FORCEPROP 1 LAST HDL_TAP TRUE
J 0
(-1650 4400);
DISPLAY 0.872340 (-1650 4400);
DISPLAY INVISIBLE (-1650 4400);
FORCEPROP 1 LAST PATH I27
J 0
(-1977 4525);
DISPLAY 0.872340 (-1977 4525);
PAINT GREEN (-1977 4525);
DISPLAY INVISIBLE (-1977 4525);
FORCEADD TAP..1
(-2175 4275);
FORCEPROP 3 LASTPIN (-2225 4275) SIG_NAME P5E_CPU0_P1_RX_DP<3>
J 0
(-2215 4285);
DISPLAY 0.659574 (-2215 4285);
PAINT MONO (-2215 4285);
DISPLAY INVISIBLE (-2215 4285);
FORCEPROP 1 LASTPIN (-2225 4275) BN 3
J 0
(-2237 4283);
DISPLAY 0.680851 (-2237 4283);
PAINT GREEN (-2237 4283);
FORCEPROP 2 LAST CDS_LIB standard
J 0
(-2175 4275);
DISPLAY INVISIBLE (-2175 4275);
FORCEPROP 1 LAST BODY_TYPE PLUMBING
J 0
(-2175 4325);
DISPLAY 0.872340 (-2175 4325);
PAINT GREEN (-2175 4325);
DISPLAY INVISIBLE (-2175 4325);
FORCEPROP 1 LAST HDL_TAP TRUE
J 0
(-1850 4150);
DISPLAY 0.872340 (-1850 4150);
DISPLAY INVISIBLE (-1850 4150);
FORCEPROP 1 LAST PATH I28
J 0
(-2177 4275);
DISPLAY 0.872340 (-2177 4275);
PAINT GREEN (-2177 4275);
DISPLAY INVISIBLE (-2177 4275);
FORCEADD TAP..1
(-2175 4625);
FORCEPROP 3 LASTPIN (-2225 4625) SIG_NAME P5E_CPU0_P1_RX_DP<4>
J 0
(-2215 4635);
DISPLAY 0.659574 (-2215 4635);
PAINT MONO (-2215 4635);
DISPLAY INVISIBLE (-2215 4635);
FORCEPROP 1 LASTPIN (-2225 4625) BN 4
J 0
(-2237 4633);
DISPLAY 0.680851 (-2237 4633);
PAINT GREEN (-2237 4633);
FORCEPROP 2 LAST CDS_LIB standard
J 0
(-2175 4625);
DISPLAY INVISIBLE (-2175 4625);
FORCEPROP 1 LAST BODY_TYPE PLUMBING
J 0
(-2175 4675);
DISPLAY 0.872340 (-2175 4675);
PAINT GREEN (-2175 4675);
DISPLAY INVISIBLE (-2175 4675);
FORCEPROP 1 LAST HDL_TAP TRUE
J 0
(-1850 4500);
DISPLAY 0.872340 (-1850 4500);
DISPLAY INVISIBLE (-1850 4500);
FORCEPROP 1 LAST PATH I29
J 0
(-2177 4625);
DISPLAY 0.872340 (-2177 4625);
PAINT GREEN (-2177 4625);
DISPLAY INVISIBLE (-2177 4625);
FORCEADD TAP..1
(-6525 3125);
FORCEPROP 3 LASTPIN (-6575 3125) SIG_NAME P5E_CPU0_P1_RX_DN<8>
J 0
(-6565 3135);
DISPLAY 0.659574 (-6565 3135);
PAINT MONO (-6565 3135);
DISPLAY INVISIBLE (-6565 3135);
FORCEPROP 1 LASTPIN (-6575 3125) BN 8
J 0
(-6587 3133);
DISPLAY 0.680851 (-6587 3133);
PAINT GREEN (-6587 3133);
FORCEPROP 2 LAST CDS_LIB standard
J 0
(-6525 3125);
DISPLAY INVISIBLE (-6525 3125);
FORCEPROP 1 LAST BODY_TYPE PLUMBING
J 0
(-6525 3175);
DISPLAY 0.872340 (-6525 3175);
PAINT GREEN (-6525 3175);
DISPLAY INVISIBLE (-6525 3175);
FORCEPROP 1 LAST HDL_TAP TRUE
J 0
(-6200 3000);
DISPLAY 0.872340 (-6200 3000);
DISPLAY INVISIBLE (-6200 3000);
FORCEPROP 1 LAST PATH I3
J 0
(-6527 3125);
DISPLAY 0.872340 (-6527 3125);
PAINT GREEN (-6527 3125);
DISPLAY INVISIBLE (-6527 3125);
FORCEADD TAP..1
(-2175 4975);
FORCEPROP 3 LASTPIN (-2225 4975) SIG_NAME P5E_CPU0_P1_RX_DP<5>
J 0
(-2215 4985);
DISPLAY 0.659574 (-2215 4985);
PAINT MONO (-2215 4985);
DISPLAY INVISIBLE (-2215 4985);
FORCEPROP 1 LASTPIN (-2225 4975) BN 5
J 0
(-2237 4983);
DISPLAY 0.680851 (-2237 4983);
PAINT GREEN (-2237 4983);
FORCEPROP 2 LAST CDS_LIB standard
J 0
(-2175 4975);
DISPLAY INVISIBLE (-2175 4975);
FORCEPROP 1 LAST BODY_TYPE PLUMBING
J 0
(-2175 5025);
DISPLAY 0.872340 (-2175 5025);
PAINT GREEN (-2175 5025);
DISPLAY INVISIBLE (-2175 5025);
FORCEPROP 1 LAST HDL_TAP TRUE
J 0
(-1850 4850);
DISPLAY 0.872340 (-1850 4850);
DISPLAY INVISIBLE (-1850 4850);
FORCEPROP 1 LAST PATH I30
J 0
(-2177 4975);
DISPLAY 0.872340 (-2177 4975);
PAINT GREEN (-2177 4975);
DISPLAY INVISIBLE (-2177 4975);
FORCEADD TAP..1
(-1975 4875);
FORCEPROP 3 LASTPIN (-2025 4875) SIG_NAME P5E_CPU0_P1_RX_DN<5>
J 0
(-2015 4885);
DISPLAY 0.659574 (-2015 4885);
PAINT MONO (-2015 4885);
DISPLAY INVISIBLE (-2015 4885);
FORCEPROP 1 LASTPIN (-2025 4875) BN 5
J 0
(-2037 4883);
DISPLAY 0.680851 (-2037 4883);
PAINT GREEN (-2037 4883);
FORCEPROP 2 LAST CDS_LIB standard
J 0
(-1975 4875);
DISPLAY INVISIBLE (-1975 4875);
FORCEPROP 1 LAST BODY_TYPE PLUMBING
J 0
(-1975 4925);
DISPLAY 0.872340 (-1975 4925);
PAINT GREEN (-1975 4925);
DISPLAY INVISIBLE (-1975 4925);
FORCEPROP 1 LAST HDL_TAP TRUE
J 0
(-1650 4750);
DISPLAY 0.872340 (-1650 4750);
DISPLAY INVISIBLE (-1650 4750);
FORCEPROP 1 LAST PATH I31
J 0
(-1977 4875);
DISPLAY 0.872340 (-1977 4875);
PAINT GREEN (-1977 4875);
DISPLAY INVISIBLE (-1977 4875);
FORCEADD TAP..1
(-1975 5225);
FORCEPROP 3 LASTPIN (-2025 5225) SIG_NAME P5E_CPU0_P1_RX_DN<6>
J 0
(-2015 5235);
DISPLAY 0.659574 (-2015 5235);
PAINT MONO (-2015 5235);
DISPLAY INVISIBLE (-2015 5235);
FORCEPROP 1 LASTPIN (-2025 5225) BN 6
J 0
(-2037 5233);
DISPLAY 0.680851 (-2037 5233);
PAINT GREEN (-2037 5233);
FORCEPROP 2 LAST CDS_LIB standard
J 0
(-1975 5225);
DISPLAY INVISIBLE (-1975 5225);
FORCEPROP 1 LAST BODY_TYPE PLUMBING
J 0
(-1975 5275);
DISPLAY 0.872340 (-1975 5275);
PAINT GREEN (-1975 5275);
DISPLAY INVISIBLE (-1975 5275);
FORCEPROP 1 LAST HDL_TAP TRUE
J 0
(-1650 5100);
DISPLAY 0.872340 (-1650 5100);
DISPLAY INVISIBLE (-1650 5100);
FORCEPROP 1 LAST PATH I32
J 0
(-1977 5225);
DISPLAY 0.872340 (-1977 5225);
PAINT GREEN (-1977 5225);
DISPLAY INVISIBLE (-1977 5225);
FORCEADD TAP..1
(-2175 5325);
FORCEPROP 3 LASTPIN (-2225 5325) SIG_NAME P5E_CPU0_P1_RX_DP<6>
J 0
(-2215 5335);
DISPLAY 0.659574 (-2215 5335);
PAINT MONO (-2215 5335);
DISPLAY INVISIBLE (-2215 5335);
FORCEPROP 1 LASTPIN (-2225 5325) BN 6
J 0
(-2237 5333);
DISPLAY 0.680851 (-2237 5333);
PAINT GREEN (-2237 5333);
FORCEPROP 2 LAST CDS_LIB standard
J 0
(-2175 5325);
DISPLAY INVISIBLE (-2175 5325);
FORCEPROP 1 LAST BODY_TYPE PLUMBING
J 0
(-2175 5375);
DISPLAY 0.872340 (-2175 5375);
PAINT GREEN (-2175 5375);
DISPLAY INVISIBLE (-2175 5375);
FORCEPROP 1 LAST HDL_TAP TRUE
J 0
(-1850 5200);
DISPLAY 0.872340 (-1850 5200);
DISPLAY INVISIBLE (-1850 5200);
FORCEPROP 1 LAST PATH I33
J 0
(-2177 5325);
DISPLAY 0.872340 (-2177 5325);
PAINT GREEN (-2177 5325);
DISPLAY INVISIBLE (-2177 5325);
FORCEADD TAP..1
(-2175 5675);
FORCEPROP 3 LASTPIN (-2225 5675) SIG_NAME P5E_CPU0_P1_RX_DP<7>
J 0
(-2215 5685);
DISPLAY 0.659574 (-2215 5685);
PAINT MONO (-2215 5685);
DISPLAY INVISIBLE (-2215 5685);
FORCEPROP 1 LASTPIN (-2225 5675) BN 7
J 0
(-2237 5683);
DISPLAY 0.680851 (-2237 5683);
PAINT GREEN (-2237 5683);
FORCEPROP 2 LAST CDS_LIB standard
J 0
(-2175 5675);
DISPLAY INVISIBLE (-2175 5675);
FORCEPROP 1 LAST BODY_TYPE PLUMBING
J 0
(-2175 5725);
DISPLAY 0.872340 (-2175 5725);
PAINT GREEN (-2175 5725);
DISPLAY INVISIBLE (-2175 5725);
FORCEPROP 1 LAST HDL_TAP TRUE
J 0
(-1850 5550);
DISPLAY 0.872340 (-1850 5550);
DISPLAY INVISIBLE (-1850 5550);
FORCEPROP 1 LAST PATH I34
J 0
(-2177 5675);
DISPLAY 0.872340 (-2177 5675);
PAINT GREEN (-2177 5675);
DISPLAY INVISIBLE (-2177 5675);
FORCEADD TAP..1
(-1975 5575);
FORCEPROP 3 LASTPIN (-2025 5575) SIG_NAME P5E_CPU0_P1_RX_DN<7>
J 0
(-2015 5585);
DISPLAY 0.659574 (-2015 5585);
PAINT MONO (-2015 5585);
DISPLAY INVISIBLE (-2015 5585);
FORCEPROP 1 LASTPIN (-2025 5575) BN 7
J 0
(-2037 5583);
DISPLAY 0.680851 (-2037 5583);
PAINT GREEN (-2037 5583);
FORCEPROP 2 LAST CDS_LIB standard
J 0
(-1975 5575);
DISPLAY INVISIBLE (-1975 5575);
FORCEPROP 1 LAST BODY_TYPE PLUMBING
J 0
(-1975 5625);
DISPLAY 0.872340 (-1975 5625);
PAINT GREEN (-1975 5625);
DISPLAY INVISIBLE (-1975 5625);
FORCEPROP 1 LAST HDL_TAP TRUE
J 0
(-1650 5450);
DISPLAY 0.872340 (-1650 5450);
DISPLAY INVISIBLE (-1650 5450);
FORCEPROP 1 LAST PATH I35
J 0
(-1977 5575);
DISPLAY 0.872340 (-1977 5575);
PAINT GREEN (-1977 5575);
DISPLAY INVISIBLE (-1977 5575);
FORCEADD OFFPAGE..5
R 2
(-975 5600);
FORCEPROP 2 LAST $XR0 24 
J 0
(-786 5600);
DISPLAY 0.638298 (-786 5600);
PAINT MONO (-786 5600);
FORCEPROP 2 LAST CDS_LIB standard
J 0
(-975 5600);
DISPLAY INVISIBLE (-975 5600);
FORCEPROP 1 LAST OFFPAGE TRUE
J 2
(-1300 5475);
DISPLAY 0.872340 (-1300 5475);
PAINT GREEN (-1300 5475);
DISPLAY INVISIBLE (-1300 5475);
FORCEPROP 1 LAST COMMENT_BODY TRUE
J 2
(-1075 5525);
DISPLAY 0.872340 (-1075 5525);
PAINT GREEN (-1075 5525);
DISPLAY INVISIBLE (-1075 5525);
FORCEPROP 2 LAST PATH I36
J 0
(-800 5675);
DISPLAY 0.680851 (-800 5675);
DISPLAY INVISIBLE (-800 5675);
FORCEADD OFFPAGE..5
R 2
(-975 5700);
FORCEPROP 2 LAST $XR0 24 
J 0
(-786 5700);
DISPLAY 0.638298 (-786 5700);
PAINT MONO (-786 5700);
FORCEPROP 2 LAST CDS_LIB standard
J 0
(-975 5700);
DISPLAY INVISIBLE (-975 5700);
FORCEPROP 1 LAST OFFPAGE TRUE
J 2
(-1300 5575);
DISPLAY 0.872340 (-1300 5575);
PAINT GREEN (-1300 5575);
DISPLAY INVISIBLE (-1300 5575);
FORCEPROP 1 LAST COMMENT_BODY TRUE
J 2
(-1075 5625);
DISPLAY 0.872340 (-1075 5625);
PAINT GREEN (-1075 5625);
DISPLAY INVISIBLE (-1075 5625);
FORCEPROP 2 LAST PATH I37
J 0
(-800 5775);
DISPLAY 0.680851 (-800 5775);
DISPLAY INVISIBLE (-800 5775);
FORCEADD PT5161LRS..7
(-3200 4425);
FORCEPROP 1 LAST LOCATION U6011
J 0
(-3550 6050);
DISPLAY 0.723404 (-3550 6050);
PAINT GREEN (-3550 6050);
FORCEPROP 0 LAST $SEC 7
J 0
(-3550 6200);
DISPLAY 0.680851 (-3550 6200);
PAINT MONO (-3550 6200);
DISPLAY INVISIBLE (-3550 6200);
FORCEPROP 0 LAST CDS_SEC 7
J 0
(-3550 6200);
DISPLAY 0.680851 (-3550 6200);
DISPLAY INVISIBLE (-3550 6200);
FORCEPROP 0 LASTPIN (-2750 5575) $PN CK29
J 0
(-2740 5585);
DISPLAY 0.680851 (-2740 5585);
PAINT MONO (-2740 5585);
FORCEPROP 0 LASTPIN (-2750 5225) $PN CU29
J 0
(-2740 5235);
DISPLAY 0.680851 (-2740 5235);
PAINT MONO (-2740 5235);
FORCEPROP 0 LASTPIN (-2750 4875) $PN DD29
J 0
(-2740 4885);
DISPLAY 0.680851 (-2740 4885);
PAINT MONO (-2740 4885);
FORCEPROP 0 LASTPIN (-2750 4525) $PN DL29
J 0
(-2740 4535);
DISPLAY 0.680851 (-2740 4535);
PAINT MONO (-2740 4535);
FORCEPROP 0 LASTPIN (-2750 4175) $PN DV29
J 0
(-2740 4185);
DISPLAY 0.680851 (-2740 4185);
PAINT MONO (-2740 4185);
FORCEPROP 0 LASTPIN (-2750 3825) $PN EE29
J 0
(-2740 3835);
DISPLAY 0.680851 (-2740 3835);
PAINT MONO (-2740 3835);
FORCEPROP 0 LASTPIN (-2750 3475) $PN EM29
J 0
(-2740 3485);
DISPLAY 0.680851 (-2740 3485);
PAINT MONO (-2740 3485);
FORCEPROP 0 LASTPIN (-2750 3125) $PN EW29
J 0
(-2740 3135);
DISPLAY 0.680851 (-2740 3135);
PAINT MONO (-2740 3135);
FORCEPROP 0 LASTPIN (-2750 5675) $PN CH26
J 0
(-2740 5685);
DISPLAY 0.680851 (-2740 5685);
PAINT MONO (-2740 5685);
FORCEPROP 0 LASTPIN (-2750 5325) $PN CR26
J 0
(-2740 5335);
DISPLAY 0.680851 (-2740 5335);
PAINT MONO (-2740 5335);
FORCEPROP 0 LASTPIN (-2750 4975) $PN DB26
J 0
(-2740 4985);
DISPLAY 0.680851 (-2740 4985);
PAINT MONO (-2740 4985);
FORCEPROP 0 LASTPIN (-2750 4625) $PN DJ26
J 0
(-2740 4635);
DISPLAY 0.680851 (-2740 4635);
PAINT MONO (-2740 4635);
FORCEPROP 0 LASTPIN (-2750 4275) $PN DT26
J 0
(-2740 4285);
DISPLAY 0.680851 (-2740 4285);
PAINT MONO (-2740 4285);
FORCEPROP 0 LASTPIN (-2750 3925) $PN EC26
J 0
(-2740 3935);
DISPLAY 0.680851 (-2740 3935);
PAINT MONO (-2740 3935);
FORCEPROP 0 LASTPIN (-2750 3575) $PN EK26
J 0
(-2740 3585);
DISPLAY 0.680851 (-2740 3585);
PAINT MONO (-2740 3585);
FORCEPROP 0 LASTPIN (-2750 3225) $PN EU26
J 0
(-2740 3235);
DISPLAY 0.680851 (-2740 3235);
PAINT MONO (-2740 3235);
FORCEPROP 1 LAST MATERIAL IC
J 0
(-3550 5900);
DISPLAY 0.723404 (-3550 5900);
PAINT GREEN (-3550 5900);
FORCEPROP 2 LAST PART_TYPE SMLF
J 0
(-3550 6150);
DISPLAY 0.680851 (-3550 6150);
FORCEPROP 2 LAST VALUE PT5161LRS
J 0
(-3550 6100);
DISPLAY 0.680851 (-3550 6100);
FORCEPROP 2 LAST CDS_LIB pure_quanta
J 0
(-3200 4425);
DISPLAY INVISIBLE (-3200 4425);
FORCEPROP 1 LAST CDS_LMAN_SYM_OUTLINE -350,1450,300,-1400
J 0
(-3200 4425);
DISPLAY 0.468085 (-3200 4425);
PAINT GREEN (-3200 4425);
DISPLAY INVISIBLE (-3200 4425);
FORCEPROP 1 LAST NEEDS_NO_SIZE TRUE
J 0
(-3200 4425);
DISPLAY 0.723404 (-3200 4425);
PAINT GREEN (-3200 4425);
DISPLAY INVISIBLE (-3200 4425);
FORCEPROP 1 LAST PATH I38
J 0
(-3200 4425);
DISPLAY 0.723404 (-3200 4425);
PAINT GREEN (-3200 4425);
DISPLAY INVISIBLE (-3200 4425);
FORCEPROP 1 LAST PART_NUMBER AJ051610U03
J 0
(-3550 5975);
DISPLAY 0.723404 (-3550 5975);
PAINT GREEN (-3550 5975);
DISPLAY INVISIBLE (-3550 5975);
FORCEADD TAP..1
(-6725 3575);
FORCEPROP 3 LASTPIN (-6775 3575) SIG_NAME P5E_CPU0_P1_RX_DP<9>
J 0
(-6765 3585);
DISPLAY 0.659574 (-6765 3585);
PAINT MONO (-6765 3585);
DISPLAY INVISIBLE (-6765 3585);
FORCEPROP 1 LASTPIN (-6775 3575) BN 9
J 0
(-6787 3583);
DISPLAY 0.680851 (-6787 3583);
PAINT GREEN (-6787 3583);
FORCEPROP 2 LAST CDS_LIB standard
J 0
(-6725 3575);
DISPLAY INVISIBLE (-6725 3575);
FORCEPROP 1 LAST BODY_TYPE PLUMBING
J 0
(-6725 3625);
DISPLAY 0.872340 (-6725 3625);
PAINT GREEN (-6725 3625);
DISPLAY INVISIBLE (-6725 3625);
FORCEPROP 1 LAST HDL_TAP TRUE
J 0
(-6400 3450);
DISPLAY 0.872340 (-6400 3450);
DISPLAY INVISIBLE (-6400 3450);
FORCEPROP 1 LAST PATH I4
J 0
(-6727 3575);
DISPLAY 0.872340 (-6727 3575);
PAINT GREEN (-6727 3575);
DISPLAY INVISIBLE (-6727 3575);
FORCEADD TAP..1
(-6525 3475);
FORCEPROP 3 LASTPIN (-6575 3475) SIG_NAME P5E_CPU0_P1_RX_DN<9>
J 0
(-6565 3485);
DISPLAY 0.659574 (-6565 3485);
PAINT MONO (-6565 3485);
DISPLAY INVISIBLE (-6565 3485);
FORCEPROP 1 LASTPIN (-6575 3475) BN 9
J 0
(-6587 3483);
DISPLAY 0.680851 (-6587 3483);
PAINT GREEN (-6587 3483);
FORCEPROP 2 LAST CDS_LIB standard
J 0
(-6525 3475);
DISPLAY INVISIBLE (-6525 3475);
FORCEPROP 1 LAST BODY_TYPE PLUMBING
J 0
(-6525 3525);
DISPLAY 0.872340 (-6525 3525);
PAINT GREEN (-6525 3525);
DISPLAY INVISIBLE (-6525 3525);
FORCEPROP 1 LAST HDL_TAP TRUE
J 0
(-6200 3350);
DISPLAY 0.872340 (-6200 3350);
DISPLAY INVISIBLE (-6200 3350);
FORCEPROP 1 LAST PATH I5
J 0
(-6527 3475);
DISPLAY 0.872340 (-6527 3475);
PAINT GREEN (-6527 3475);
DISPLAY INVISIBLE (-6527 3475);
FORCEADD TAP..1
(-6525 3825);
FORCEPROP 3 LASTPIN (-6575 3825) SIG_NAME P5E_CPU0_P1_RX_DN<10>
J 0
(-6565 3835);
DISPLAY 0.659574 (-6565 3835);
PAINT MONO (-6565 3835);
DISPLAY INVISIBLE (-6565 3835);
FORCEPROP 1 LASTPIN (-6575 3825) BN 10
J 0
(-6587 3833);
DISPLAY 0.680851 (-6587 3833);
PAINT GREEN (-6587 3833);
FORCEPROP 2 LAST CDS_LIB standard
J 0
(-6525 3825);
DISPLAY INVISIBLE (-6525 3825);
FORCEPROP 1 LAST BODY_TYPE PLUMBING
J 0
(-6525 3875);
DISPLAY 0.872340 (-6525 3875);
PAINT GREEN (-6525 3875);
DISPLAY INVISIBLE (-6525 3875);
FORCEPROP 1 LAST HDL_TAP TRUE
J 0
(-6200 3700);
DISPLAY 0.872340 (-6200 3700);
DISPLAY INVISIBLE (-6200 3700);
FORCEPROP 1 LAST PATH I6
J 0
(-6527 3825);
DISPLAY 0.872340 (-6527 3825);
PAINT GREEN (-6527 3825);
DISPLAY INVISIBLE (-6527 3825);
FORCEADD TAP..1
(-6725 3925);
FORCEPROP 3 LASTPIN (-6775 3925) SIG_NAME P5E_CPU0_P1_RX_DP<10>
J 0
(-6765 3935);
DISPLAY 0.659574 (-6765 3935);
PAINT MONO (-6765 3935);
DISPLAY INVISIBLE (-6765 3935);
FORCEPROP 1 LASTPIN (-6775 3925) BN 10
J 0
(-6787 3933);
DISPLAY 0.680851 (-6787 3933);
PAINT GREEN (-6787 3933);
FORCEPROP 2 LAST CDS_LIB standard
J 0
(-6725 3925);
DISPLAY INVISIBLE (-6725 3925);
FORCEPROP 1 LAST BODY_TYPE PLUMBING
J 0
(-6725 3975);
DISPLAY 0.872340 (-6725 3975);
PAINT GREEN (-6725 3975);
DISPLAY INVISIBLE (-6725 3975);
FORCEPROP 1 LAST HDL_TAP TRUE
J 0
(-6400 3800);
DISPLAY 0.872340 (-6400 3800);
DISPLAY INVISIBLE (-6400 3800);
FORCEPROP 1 LAST PATH I7
J 0
(-6727 3925);
DISPLAY 0.872340 (-6727 3925);
PAINT GREEN (-6727 3925);
DISPLAY INVISIBLE (-6727 3925);
FORCEADD TAP..1
(-6725 4275);
FORCEPROP 3 LASTPIN (-6775 4275) SIG_NAME P5E_CPU0_P1_RX_DP<11>
J 0
(-6765 4285);
DISPLAY 0.659574 (-6765 4285);
PAINT MONO (-6765 4285);
DISPLAY INVISIBLE (-6765 4285);
FORCEPROP 1 LASTPIN (-6775 4275) BN 11
J 0
(-6787 4283);
DISPLAY 0.680851 (-6787 4283);
PAINT GREEN (-6787 4283);
FORCEPROP 2 LAST CDS_LIB standard
J 0
(-6725 4275);
DISPLAY INVISIBLE (-6725 4275);
FORCEPROP 1 LAST BODY_TYPE PLUMBING
J 0
(-6725 4325);
DISPLAY 0.872340 (-6725 4325);
PAINT GREEN (-6725 4325);
DISPLAY INVISIBLE (-6725 4325);
FORCEPROP 1 LAST HDL_TAP TRUE
J 0
(-6400 4150);
DISPLAY 0.872340 (-6400 4150);
DISPLAY INVISIBLE (-6400 4150);
FORCEPROP 1 LAST PATH I8
J 0
(-6727 4275);
DISPLAY 0.872340 (-6727 4275);
PAINT GREEN (-6727 4275);
DISPLAY INVISIBLE (-6727 4275);
FORCEADD TAP..1
(-6525 4175);
FORCEPROP 3 LASTPIN (-6575 4175) SIG_NAME P5E_CPU0_P1_RX_DN<11>
J 0
(-6565 4185);
DISPLAY 0.659574 (-6565 4185);
PAINT MONO (-6565 4185);
DISPLAY INVISIBLE (-6565 4185);
FORCEPROP 1 LASTPIN (-6575 4175) BN 11
J 0
(-6587 4183);
DISPLAY 0.680851 (-6587 4183);
PAINT GREEN (-6587 4183);
FORCEPROP 2 LAST CDS_LIB standard
J 0
(-6525 4175);
DISPLAY INVISIBLE (-6525 4175);
FORCEPROP 1 LAST BODY_TYPE PLUMBING
J 0
(-6525 4225);
DISPLAY 0.872340 (-6525 4225);
PAINT GREEN (-6525 4225);
DISPLAY INVISIBLE (-6525 4225);
FORCEPROP 1 LAST HDL_TAP TRUE
J 0
(-6200 4050);
DISPLAY 0.872340 (-6200 4050);
DISPLAY INVISIBLE (-6200 4050);
FORCEPROP 1 LAST PATH I9
J 0
(-6527 4175);
DISPLAY 0.872340 (-6527 4175);
PAINT GREEN (-6527 4175);
DISPLAY INVISIBLE (-6527 4175);
FORCEADD QUANTA_TITLE_BLOCK_C..1
(0 0);
FORCEPROP 0 LAST CDS_CON_LAST_MODIFIED Thu Sep 14 16:12:51 2023
J 0
(-1885 15);
DISPLAY INVISIBLE (-1885 15);
FORCEPROP 1 LAST CUSTOM_TXT_CDS <CON_LAST_MODIFIED>
J 0
(-1885 15);
DISPLAY 0.978723 (-1885 15);
FORCEPROP 2 LAST CUSTOM_TXT_CDS <XR_PAGE_TITLE>
J 0
(-7890 5250);
DISPLAY 0.638298 (-7890 5250);
PAINT PINK (-7890 5250);
DISPLAY INVISIBLE (-7890 5250);
FORCEPROP 1 LAST CUSTOM_TXT_CDS <NAME_2>
J 0
(-3175 50);
FORCEPROP 1 LAST CUSTOM_TXT_CDS <NAME_1>
J 0
(-3175 175);
FORCEPROP 1 LAST CUSTOM_TXT_CDS <Q_NUMBER>
J 0
(-1403 103);
DISPLAY 1.212766 (-1403 103);
FORCEPROP 1 LAST CUSTOM_TXT_CDS <Q_PROJ>
J 0
(-2382 102);
DISPLAY 1.212766 (-2382 102);
FORCEPROP 1 LAST CUSTOM_TXT_CDS <Q_REV>
J 0
(-184 103);
DISPLAY 1.212766 (-184 103);
FORCEPROP 1 LAST CUSTOM_TXT_CDS <CON_PAGE_NUM> OF <CON_TOTAL_PAGES>
J 0
(-446 18);
DISPLAY 0.978723 (-446 18);
FORCEPROP 1 LAST Q_TITLE RETIMER_CPU0_P1(2)
J 0
(-9366 26);
DISPLAY 2.446809 (-9366 26);
PAINT GREEN (-9366 26);
FORCEPROP 2 LAST PAGE_BORDER TRUE
J 0
(-7890 5250);
DISPLAY 0.638298 (-7890 5250);
PAINT PINK (-7890 5250);
DISPLAY INVISIBLE (-7890 5250);
FORCEPROP 1 LAST CDS_LMAN_SYM_OUTLINE -9475,6775,100,-125
J 0
(0 0);
DISPLAY 0.468085 (0 0);
PAINT GREEN (0 0);
DISPLAY INVISIBLE (0 0);
FORCEPROP 2 LAST CDS_LIB pure_quanta
J 0
(0 0);
DISPLAY INVISIBLE (0 0);
FORCEPROP 2 LAST CDS_XR_PAGE_TITLE CR-285 : @T6G_MB_LIB.T6G(SCH_1):PAGE285
J 0
(-7890 5250);
DISPLAY 0.638298 (-7890 5250);
PAINT PINK (-7890 5250);
DISPLAY INVISIBLE (-7890 5250);
FORCEPROP 1 LAST Q_DEPT BU9
J 1
(-3763 49);
DISPLAY 1.957447 (-3763 49);
PAINT GREEN (-3763 49);
DISPLAY INVISIBLE (-3763 49);
FORCEPROP 1 LAST COMMENT_BODY TRUE
J 0
(12 -13);
DISPLAY 0.978723 (12 -13);
PAINT GREEN (12 -13);
DISPLAY INVISIBLE (12 -13);
WIRE 17 -1 (-6675 3600)(-6675 3250);
WIRE 17 -1 (-6675 3950)(-6675 3600);
WIRE 17 -1 (-6675 4300)(-6675 3950);
WIRE 17 -1 (-6675 4300)(-6675 4650);
WIRE 17 -1 (-6675 5000)(-6675 4650);
WIRE 17 -1 (-6675 5350)(-6675 5000);
WIRE 17 -1 (-6675 5700)(-6675 5350);
WIRE 17 -1 (-6675 5775)(-6675 5700);
WIRE 17 -1 (-6675 5775)(-5550 5775);
FORCEPROP 2 LAST SIG_NAME P5E_CPU0_P1_RX_DP<15:8>
J 0
(-6410 5785);
DISPLAY 0.680851 (-6410 5785);
PAINT WHITE (-6410 5785);
WIRE 17 -1 (-2125 5700)(-2125 5350);
WIRE 17 -1 (-2125 5700)(-1025 5700);
FORCEPROP 2 LAST SIG_NAME P5E_CPU0_P1_RX_DP<7:0>
J 0
(-1860 5710);
DISPLAY 0.680851 (-1860 5710);
PAINT WHITE (-1860 5710);
WIRE 17 -1 (-2125 3600)(-2125 3250);
WIRE 17 -1 (-2125 3950)(-2125 3600);
WIRE 17 -1 (-2125 4300)(-2125 3950);
WIRE 17 -1 (-2125 4300)(-2125 4650);
WIRE 17 -1 (-2125 5000)(-2125 4650);
WIRE 17 -1 (-2125 5350)(-2125 5000);
WIRE 17 -1 (-1925 4200)(-1925 4550);
WIRE 17 -1 (-1925 4200)(-1925 3850);
WIRE 17 -1 (-1925 4900)(-1925 4550);
WIRE 17 -1 (-1925 5250)(-1925 4900);
WIRE 17 -1 (-1925 3850)(-1925 3500);
WIRE 17 -1 (-1925 3500)(-1925 3150);
WIRE 17 -1 (-1925 5600)(-1925 5250);
WIRE 17 -1 (-1925 5600)(-1025 5600);
FORCEPROP 2 LAST SIG_NAME P5E_CPU0_P1_RX_DN<7:0>
J 0
(-1860 5610);
DISPLAY 0.680851 (-1860 5610);
PAINT WHITE (-1860 5610);
WIRE 17 -1 (-6475 4200)(-6475 4550);
WIRE 17 -1 (-6475 4200)(-6475 3850);
WIRE 17 -1 (-6475 4900)(-6475 4550);
WIRE 17 -1 (-6475 5250)(-6475 4900);
WIRE 17 -1 (-6475 3850)(-6475 3500);
WIRE 17 -1 (-6475 3500)(-6475 3150);
WIRE 17 -1 (-6475 5600)(-6475 5250);
WIRE 17 -1 (-6475 5650)(-6475 5600);
WIRE 17 -1 (-6475 5650)(-5575 5650);
FORCEPROP 2 LAST SIG_NAME P5E_CPU0_P1_RX_DN<15:8>
J 0
(-6410 5660);
DISPLAY 0.680851 (-6410 5660);
PAINT WHITE (-6410 5660);
WIRE 16 -1 (-7300 5675)(-6775 5675);
WIRE 16 -1 (-7300 5575)(-6575 5575);
WIRE 16 -1 (-7300 5325)(-6775 5325);
WIRE 16 -1 (-7300 5225)(-6575 5225);
WIRE 16 -1 (-7300 4525)(-6575 4525);
WIRE 16 -1 (-2750 3825)(-2025 3825);
WIRE 16 -1 (-2750 4175)(-2025 4175);
WIRE 16 -1 (-2750 3475)(-2025 3475);
WIRE 16 -1 (-2750 3125)(-2025 3125);
WIRE 16 -1 (-2750 4875)(-2025 4875);
WIRE 16 -1 (-2750 5225)(-2025 5225);
WIRE 16 -1 (-2750 5575)(-2025 5575);
WIRE 16 -1 (-7300 4875)(-6575 4875);
WIRE 16 -1 (-7300 3475)(-6575 3475);
WIRE 16 -1 (-7300 3825)(-6575 3825);
WIRE 16 -1 (-7300 3125)(-6575 3125);
WIRE 16 -1 (-7300 4175)(-6575 4175);
WIRE 16 -1 (-2750 4525)(-2025 4525);
WIRE 16 -1 (-2750 4275)(-2225 4275);
WIRE 16 -1 (-2750 3575)(-2225 3575);
WIRE 16 -1 (-2750 4975)(-2225 4975);
WIRE 16 -1 (-2750 4625)(-2225 4625);
WIRE 16 -1 (-2750 3925)(-2225 3925);
WIRE 16 -1 (-2750 3225)(-2225 3225);
WIRE 16 -1 (-2750 5675)(-2225 5675);
WIRE 16 -1 (-2750 5325)(-2225 5325);
WIRE 16 -1 (-7300 3575)(-6775 3575);
WIRE 16 -1 (-7300 3925)(-6775 3925);
WIRE 16 -1 (-7300 4275)(-6775 4275);
WIRE 16 -1 (-7300 4625)(-6775 4625);
WIRE 16 -1 (-7300 4975)(-6775 4975);
WIRE 16 -1 (-7300 3225)(-6775 3225);
FORCENOTE
P5E_CPU0_P1_RX_DP/DN<0-15> LANE REVERSAL
(-9000 6325) 0;
DISPLAY LEFT (-9000 6325);
DISPLAY 2.000000 (-9000 6325);
FORCENOTE
RETIMER TO CPU
(-8100 2650) 0;
DISPLAY LEFT (-8100 2650);
DISPLAY 3.148936 (-8100 2650);
FORCENOTE
RETIMER TO CPU
(-3600 2650) 0;
DISPLAY LEFT (-3600 2650);
DISPLAY 3.148936 (-3600 2650);
QUIT
